# BASEBOARD_FAB2 (Tioga Pass) — schematic netlist excerpt (pin names and nets, part order shuffled) for the footprints in the layout excerpt that follows; sources: Cadence DE-HDL packaged netlist, KiCad conversion of Wiwynn_Tioga_Pass_MB.brd

R5D1  RES  90.9 1% CHIP  pkg 0402  page 21 : A = A_CPU0_DEF_RCOMP0 ; B = GND
RT33  RES  0 5.0% CHIP  pkg 0603  page 216 : A = VR_PVDDQ_ABC_PH1_BOOT ; B = VR_PVDDQ_ABC_PH1_BOOT_R
R3F6  RES  0.0 5% EMPTY  pkg 0402  page 104 : A = CLK_322M_156M_CPU1_OSC_VRM_DP ; B = CLK_322M_OSC_CPU1_RC_DP

(kicad_pcb
	(version 20260206)
	(generator "pcbnew")
	(generator_version "10.0")
	(general
		(thickness 1.6)
		(legacy_teardrops no)
	)
	(paper "A4")
	(title_block
		(title "Wiwynn_Tioga_Pass_MB.brd")
		(comment 1 "Tioga Pass / footprints 1984-1986 of 4770")
	)
	(layers
		(0 "F.Cu" signal "TOP")
		(4 "In1.Cu" signal "L2GND")
		(6 "In2.Cu" signal "L3")
		(8 "In3.Cu" signal "L4GND")
		(10 "In4.Cu" signal "L5")
		(12 "In5.Cu" signal "L6GND")
		(14 "In6.Cu" signal "L7VCC")
		(16 "In7.Cu" signal "L8VCC")
		(18 "In8.Cu" signal "L9GND")
		(20 "In9.Cu" signal "L10")
		(22 "In10.Cu" signal "L11GND")
		(24 "In11.Cu" signal "L12")
		(26 "In12.Cu" signal "L13GND")
		(2 "B.Cu" signal "BOTTOM")
		(9 "F.Adhes" user "F.Adhesive")
		(11 "B.Adhes" user "B.Adhesive")
		(13 "F.Paste" user "Package Geometry/Pastemask Top")
		(15 "B.Paste" user "Package Geometry/Pastemask Bottom")
		(5 "F.SilkS" user "Ref Des/Silkscreen Top")
		(7 "B.SilkS" user "Ref Des/Silkscreen Bottom")
		(1 "F.Mask" user "Board Geometry/Soldermask Top")
		(3 "B.Mask" user "Board Geometry/Soldermask Bottom")
		(17 "Dwgs.User" user "User.Drawings")
		(19 "Cmts.User" user "User.Comments")
		(21 "Eco1.User" user "User.Eco1")
		(23 "Eco2.User" user "User.Eco2")
		(25 "Edge.Cuts" user "Board Geometry/Outline")
		(27 "Margin" user)
		(31 "F.CrtYd" user "Package Geometry/Place Bound Top")
		(29 "B.CrtYd" user "Package Geometry/Place Bound Bottom")
		(35 "F.Fab" user "Ref Des/Assembly Top")
		(33 "B.Fab" user "Ref Des/Assembly Bottom")
	)
	(footprint ""
		(layer "F.Cu")
		(at 155.194 -27.9908 -90)
		(property "Reference" "R3F6"
			(at 0 0 270)
			(layer "F.SilkS")
			(hide yes)
			(effects
				(font
					(size 1.27 1.27)
				)
			)
		)
		(property "Value" ""
			(at 0 0 270)
			(layer "F.Fab")
			(effects
				(font
					(size 1.27 1.27)
				)
			)
		)
		(duplicate_pad_numbers_are_jumpers no)
		(fp_poly
			(pts
				(xy -0.2794 -0.1016) (xy 0.2794 -0.1016) (xy 0.2794 0.9906) (xy -0.2794 0.9906)
			)
			(stroke
				(width 0)
				(type default)
			)
			(fill no)
			(layer "F.CrtYd")
		)
		(fp_line
			(start -0.2794 0.9906)
			(end 0.2794 0.9906)
			(stroke
				(width 0.1)
				(type default)
			)
			(layer "F.Fab")
		)
		(fp_line
			(start 0.2794 0.9906)
			(end 0.2794 -0.1016)
			(stroke
				(width 0.1)
				(type default)
			)
			(layer "F.Fab")
		)
		(fp_line
			(start -0.2794 -0.1016)
			(end -0.2794 0.9906)
			(stroke
				(width 0.1)
				(type default)
			)
			(layer "F.Fab")
		)
		(fp_line
			(start 0.2794 -0.1016)
			(end -0.2794 -0.1016)
			(stroke
				(width 0.1)
				(type default)
			)
			(layer "F.Fab")
		)
		(pad "1" smd rect
			(at 0 0 270)
			(size 0.508 0.508)
			(layers "F.Cu" "F.Mask" "F.Paste")
			(net "CLK_322M_156M_CPU1_OSC_VRM_DP")
		)
		(pad "2" smd rect
			(at 0 0.889 270)
			(size 0.508 0.508)
			(layers "F.Cu" "F.Mask" "F.Paste")
			(net "CLK_322M_OSC_CPU1_RC_DP")
		)
		(zone
			(layer "F.Cu")
			(hatch none 0.5)
			(connect_pads
				(clearance 0)
			)
			(min_thickness 0.25)
			(keepout
				(tracks not_allowed)
				(vias allowed)
				(pads allowed)
				(copperpour not_allowed)
				(footprints allowed)
			)
			(placement
				(enabled no)
				(sheetname "")
			)
			(fill
				(thermal_gap 0.5)
				(thermal_bridge_width 0.5)
				(island_removal_mode 0)
			)
			(polygon
				(pts
					(xy 154.559 -28.2448) (xy 154.559 -27.7368) (xy 154.94 -27.7368) (xy 154.94 -28.2448)
				)
			)
		)
		(zone
			(layer "F.Cu")
			(hatch none 0.5)
			(connect_pads
				(clearance 0)
			)
			(min_thickness 0.25)
			(keepout
				(tracks allowed)
				(vias not_allowed)
				(pads allowed)
				(copperpour not_allowed)
				(footprints allowed)
			)
			(placement
				(enabled no)
				(sheetname "")
			)
			(fill
				(thermal_gap 0.5)
				(thermal_bridge_width 0.5)
				(island_removal_mode 0)
			)
			(polygon
				(pts
					(xy 154.94 -28.2448) (xy 154.94 -27.7368) (xy 154.559 -27.7368) (xy 154.559 -28.2448)
				)
			)
		)
	)
	(footprint ""
		(layer "F.Cu")
		(at 275.48332 -83.88604)
		(property "Reference" "R5D1"
			(at 0 0 0)
			(layer "F.SilkS")
			(hide yes)
			(effects
				(font
					(size 1.27 1.27)
				)
			)
		)
		(property "Value" ""
			(at 0 0 0)
			(layer "F.Fab")
			(effects
				(font
					(size 1.27 1.27)
				)
			)
		)
		(duplicate_pad_numbers_are_jumpers no)
		(fp_poly
			(pts
				(xy -0.2794 -0.1016) (xy 0.2794 -0.1016) (xy 0.2794 0.9906) (xy -0.2794 0.9906)
			)
			(stroke
				(width 0)
				(type default)
			)
			(fill no)
			(layer "F.CrtYd")
		)
		(fp_line
			(start -0.2794 -0.1016)
			(end -0.2794 0.9906)
			(stroke
				(width 0.1)
				(type default)
			)
			(layer "F.Fab")
		)
		(fp_line
			(start -0.2794 0.9906)
			(end 0.2794 0.9906)
			(stroke
				(width 0.1)
				(type default)
			)
			(layer "F.Fab")
		)
		(fp_line
			(start 0.2794 -0.1016)
			(end -0.2794 -0.1016)
			(stroke
				(width 0.1)
				(type default)
			)
			(layer "F.Fab")
		)
		(fp_line
			(start 0.2794 0.9906)
			(end 0.2794 -0.1016)
			(stroke
				(width 0.1)
				(type default)
			)
			(layer "F.Fab")
		)
		(pad "1" smd rect
			(at 0 0)
			(size 0.508 0.508)
			(layers "F.Cu" "F.Mask" "F.Paste")
			(net "A_CPU0_DEF_RCOMP0")
		)
		(pad "2" smd rect
			(at 0 0.889)
			(size 0.508 0.508)
			(layers "F.Cu" "F.Mask" "F.Paste")
			(net "GND")
		)
		(zone
			(layer "F.Cu")
			(hatch none 0.5)
			(connect_pads
				(clearance 0)
			)
			(min_thickness 0.25)
			(keepout
				(tracks allowed)
				(vias not_allowed)
				(pads allowed)
				(copperpour not_allowed)
				(footprints allowed)
			)
			(placement
				(enabled no)
				(sheetname "")
			)
			(fill
				(thermal_gap 0.5)
				(thermal_bridge_width 0.5)
				(island_removal_mode 0)
			)
			(polygon
				(pts
					(xy 275.22932 -83.63204) (xy 275.73732 -83.63204) (xy 275.73732 -83.25104) (xy 275.22932 -83.25104)
				)
			)
		)
		(zone
			(layer "F.Cu")
			(hatch none 0.5)
			(connect_pads
				(clearance 0)
			)
			(min_thickness 0.25)
			(keepout
				(tracks not_allowed)
				(vias allowed)
				(pads allowed)
				(copperpour not_allowed)
				(footprints allowed)
			)
			(placement
				(enabled no)
				(sheetname "")
			)
			(fill
				(thermal_gap 0.5)
				(thermal_bridge_width 0.5)
				(island_removal_mode 0)
			)
			(polygon
				(pts
					(xy 275.22932 -83.25104) (xy 275.73732 -83.25104) (xy 275.73732 -83.63204) (xy 275.22932 -83.63204)
				)
			)
		)
	)
	(footprint ""
		(layer "F.Cu")
		(at 351.410524 -4.296918 180)
		(property "Reference" "RT33"
			(at 1.01473 0.656336 90)
			(unlocked yes)
			(layer "F.SilkS")
			(effects
				(font
					(size 0.4064 0.254)
					(thickness 0.1524)
				)
			)
		)
		(property "Value" ""
			(at 0 0 180)
			(layer "F.Fab")
			(effects
				(font
					(size 1.27 1.27)
				)
			)
		)
		(duplicate_pad_numbers_are_jumpers no)
		(fp_poly
			(pts
				(xy -0.4953 -0.2032) (xy 0.4953 -0.2032) (xy 0.4953 1.6002) (xy -0.4953 1.6002)
			)
			(stroke
				(width 0)
				(type default)
			)
			(fill no)
			(layer "F.CrtYd")
		)
		(fp_line
			(start 0.4953 1.6002)
			(end -0.4953 1.6002)
			(stroke
				(width 0.1)
				(type default)
			)
			(layer "F.Fab")
		)
		(fp_line
			(start 0.4953 -0.2032)
			(end 0.4953 1.6002)
			(stroke
				(width 0.1)
				(type default)
			)
			(layer "F.Fab")
		)
		(fp_line
			(start -0.4953 1.6002)
			(end -0.4953 -0.2032)
			(stroke
				(width 0.1)
				(type default)
			)
			(layer "F.Fab")
		)
		(fp_line
			(start -0.4953 -0.2032)
			(end 0.4953 -0.2032)
			(stroke
				(width 0.1)
				(type default)
			)
			(layer "F.Fab")
		)
		(pad "1" smd rect
			(at 0 0 180)
			(size 0.762 0.889)
			(layers "F.Cu" "F.Mask" "F.Paste")
			(net "VR_PVDDQ_ABC_PH1_BOOT")
		)
		(pad "2" smd rect
			(at 0 1.397 180)
			(size 0.762 0.889)
			(layers "F.Cu" "F.Mask" "F.Paste")
			(net "VR_PVDDQ_ABC_PH1_BOOT_R")
		)
		(zone
			(layer "F.Cu")
			(hatch none 0.5)
			(connect_pads
				(clearance 0)
			)
			(min_thickness 0.25)
			(keepout
				(tracks allowed)
				(vias not_allowed)
				(pads allowed)
				(copperpour not_allowed)
				(footprints allowed)
			)
			(placement
				(enabled no)
				(sheetname "")
			)
			(fill
				(thermal_gap 0.5)
				(thermal_bridge_width 0.5)
				(island_removal_mode 0)
			)
			(polygon
				(pts
					(xy 351.029524 -5.249418) (xy 351.029524 -4.741418) (xy 351.791524 -4.741418) (xy 351.791524 -5.249418)
				)
			)
		)
		(zone
			(layer "F.Cu")
			(hatch none 0.5)
			(connect_pads
				(clearance 0)
			)
			(min_thickness 0.25)
			(keepout
				(tracks not_allowed)
				(vias allowed)
				(pads allowed)
				(copperpour not_allowed)
				(footprints allowed)
			)
			(placement
				(enabled no)
				(sheetname "")
			)
			(fill
				(thermal_gap 0.5)
				(thermal_bridge_width 0.5)
				(island_removal_mode 0)
			)
			(polygon
				(pts
					(xy 351.791524 -5.249418) (xy 351.029524 -5.249418) (xy 351.029524 -4.741418) (xy 351.791524 -4.741418)
				)
			)
		)
	)
)
